(kicad_pcb
	(version 20260206)
	(generator "pcbnew")
	(generator_version "10.0")
	(general
		(thickness 1.6)
		(legacy_teardrops no)
	)
	(paper "A4")
	(title_block
		(title "Bryce Canyon_R.DPB_16317-1_OCP.brd")
		(comment 1 "Bryce Canyon / footprints 815-821 of 2099")
	)
	(layers
		(0 "F.Cu" signal "TOP")
		(4 "In1.Cu" signal "L2GND")
		(6 "In2.Cu" signal "L3")
		(8 "In3.Cu" signal "L4VCC")
		(10 "In4.Cu" signal "L5VCC")
		(12 "In5.Cu" signal "L6")
		(14 "In6.Cu" signal "L7GND")
		(2 "B.Cu" signal "BOTTOM")
		(9 "F.Adhes" user "F.Adhesive")
		(11 "B.Adhes" user "B.Adhesive")
		(13 "F.Paste" user "Package Geometry/Pastemask Top")
		(15 "B.Paste" user "Package Geometry/Pastemask Bottom")
		(5 "F.SilkS" user "Ref Des/Silkscreen Top")
		(7 "B.SilkS" user "Ref Des/Silkscreen Bottom")
		(1 "F.Mask" user "Board Geometry/Soldermask Top")
		(3 "B.Mask" user "Board Geometry/Soldermask Bottom")
		(17 "Dwgs.User" user "User.Drawings")
		(19 "Cmts.User" user "User.Comments")
		(21 "Eco1.User" user "User.Eco1")
		(23 "Eco2.User" user "User.Eco2")
		(25 "Edge.Cuts" user "Board Geometry/Outline")
		(27 "Margin" user)
		(31 "F.CrtYd" user "Package Geometry/Place Bound Top")
		(29 "B.CrtYd" user "Package Geometry/Place Bound Bottom")
		(35 "F.Fab" user "Ref Des/Assembly Top")
		(33 "B.Fab" user "Ref Des/Assembly Bottom")
	)
	(footprint ""
		(layer "F.Cu")
		(at 81.534 -16.637)
		(property "Reference" "R685"
			(at 0 0 0)
			(layer "F.SilkS")
			(hide yes)
			(effects
				(font
					(size 1.27 1.27)
				)
			)
		)
		(property "Value" "0R2J-2-GP"
			(at 0.064008 -3.993896 0)
			(unlocked yes)
			(layer "F.Fab")
			(hide yes)
			(effects
				(font
					(size 1.016 1.016)
					(thickness 0.1524)
				)
			)
		)
		(property "Device Type" "R402H16"
			(at 0.064008 -5.517896 0)
			(unlocked yes)
			(layer "F.Fab")
			(hide yes)
			(effects
				(font
					(size 1.016 1.016)
					(thickness 0.1524)
				)
			)
		)
		(duplicate_pad_numbers_are_jumpers no)
		(fp_line
			(start -0.508 -0.9398)
			(end -0.508 0.9398)
			(stroke
				(width 0.1524)
				(type default)
			)
			(layer "F.SilkS")
		)
		(fp_line
			(start 0.508 -0.9398)
			(end -0.508 -0.9398)
			(stroke
				(width 0.1524)
				(type default)
			)
			(layer "F.SilkS")
		)
		(fp_rect
			(start -0.508 0.9398)
			(end 0.508 -0.9398)
			(stroke
				(width 0)
				(type default)
			)
			(fill no)
			(layer "F.CrtYd")
		)
		(fp_rect
			(start -0.508 0.9398)
			(end 0.508 -0.9398)
			(stroke
				(width 0)
				(type default)
			)
			(fill no)
			(layer "F.Fab")
		)
		(pad "1" smd custom
			(at 0 -0.4445)
			(size 0.1397 0.1397)
			(layers "F.Cu" "F.Mask" "F.Paste")
			(net "SW_HDD_G26")
			(options
				(clearance outline)
				(anchor circle)
			)
			(primitives
				(gr_poly
					(pts
						(arc
							(start -0.1778 -0.2794)
							(mid -0.249642 -0.249642)
							(end -0.2794 -0.1778)
						)
						(arc
							(start -0.2794 0.1778)
							(mid -0.249642 0.249642)
							(end -0.1778 0.2794)
						)
						(arc
							(start 0.1778 0.2794)
							(mid 0.249642 0.249642)
							(end 0.2794 0.1778)
						)
						(arc
							(start 0.2794 -0.1778)
							(mid 0.249642 -0.249642)
							(end 0.1778 -0.2794)
						)
					)
					(width 0)
					(fill yes)
				)
			)
		)
		(pad "2" smd custom
			(at 0 0.4445)
			(size 0.1397 0.1397)
			(layers "F.Cu" "F.Mask" "F.Paste")
			(net "SW_HDD_R26")
			(options
				(clearance outline)
				(anchor circle)
			)
			(primitives
				(gr_poly
					(pts
						(arc
							(start -0.1778 -0.2794)
							(mid -0.249642 -0.249642)
							(end -0.2794 -0.1778)
						)
						(arc
							(start -0.2794 0.1778)
							(mid -0.249642 0.249642)
							(end -0.1778 0.2794)
						)
						(arc
							(start 0.1778 0.2794)
							(mid 0.249642 0.249642)
							(end 0.2794 0.1778)
						)
						(arc
							(start 0.2794 -0.1778)
							(mid 0.249642 -0.249642)
							(end 0.1778 -0.2794)
						)
					)
					(width 0)
					(fill yes)
				)
			)
		)
	)
	(footprint ""
		(layer "F.Cu")
		(at 54.1528 -99.314)
		(property "Reference" "R390"
			(at 0 0 0)
			(layer "F.SilkS")
			(hide yes)
			(effects
				(font
					(size 1.27 1.27)
				)
			)
		)
		(property "Value" "130R3F-GP"
			(at -0.0254 -2.5146 0)
			(unlocked yes)
			(layer "F.Fab")
			(hide yes)
			(effects
				(font
					(size 1.016 1.016)
					(thickness 0.1524)
				)
			)
		)
		(property "Device Type" "R603H22"
			(at -0.0254 -4.0386 0)
			(unlocked yes)
			(layer "F.Fab")
			(hide yes)
			(effects
				(font
					(size 1.016 1.016)
					(thickness 0.1524)
				)
			)
		)
		(duplicate_pad_numbers_are_jumpers no)
		(fp_line
			(start -0.4826 0)
			(end -0.2032 0)
			(stroke
				(width 0.2032)
				(type default)
			)
			(layer "F.SilkS")
		)
		(fp_line
			(start 0.2032 0)
			(end 0.4826 0)
			(stroke
				(width 0.2032)
				(type default)
			)
			(layer "F.SilkS")
		)
		(fp_rect
			(start -0.5842 1.3335)
			(end 0.5842 -1.3335)
			(stroke
				(width 0)
				(type default)
			)
			(fill no)
			(layer "F.CrtYd")
		)
		(fp_rect
			(start -0.5842 1.3335)
			(end 0.5842 -1.3335)
			(stroke
				(width 0)
				(type default)
			)
			(fill no)
			(layer "F.Fab")
		)
		(pad "1" smd custom
			(at 0 -0.762)
			(size 0.2159 0.2159)
			(layers "F.Cu" "F.Mask" "F.Paste")
			(net "P5V_B_1")
			(options
				(clearance outline)
				(anchor circle)
			)
			(primitives
				(gr_poly
					(pts
						(arc
							(start -0.3302 -0.4318)
							(mid -0.402042 -0.402042)
							(end -0.4318 -0.3302)
						)
						(arc
							(start -0.4318 0.3302)
							(mid -0.402042 0.402042)
							(end -0.3302 0.4318)
						)
						(arc
							(start 0.3302 0.4318)
							(mid 0.402042 0.402042)
							(end 0.4318 0.3302)
						)
						(arc
							(start 0.4318 -0.3302)
							(mid 0.402042 -0.402042)
							(end 0.3302 -0.4318)
						)
					)
					(width 0)
					(fill yes)
				)
			)
		)
		(pad "2" smd custom
			(at 0 0.762)
			(size 0.2159 0.2159)
			(layers "F.Cu" "F.Mask" "F.Paste")
			(net "FLT_HDD13")
			(options
				(clearance outline)
				(anchor circle)
			)
			(primitives
				(gr_poly
					(pts
						(arc
							(start -0.3302 -0.4318)
							(mid -0.402042 -0.402042)
							(end -0.4318 -0.3302)
						)
						(arc
							(start -0.4318 0.3302)
							(mid -0.402042 0.402042)
							(end -0.3302 0.4318)
						)
						(arc
							(start 0.3302 0.4318)
							(mid 0.402042 0.402042)
							(end 0.4318 0.3302)
						)
						(arc
							(start 0.4318 -0.3302)
							(mid 0.402042 -0.402042)
							(end 0.3302 -0.4318)
						)
					)
					(width 0)
					(fill yes)
				)
			)
		)
	)
	(footprint ""
		(layer "F.Cu")
		(at 455.93 -45.339 180)
		(property "Reference" "C479"
			(at 0 0 180)
			(layer "F.SilkS")
			(hide yes)
			(effects
				(font
					(size 1.27 1.27)
				)
			)
		)
		(property "Value" "SC1U25V3KX-GP"
			(at 0 -2.8194 180)
			(unlocked yes)
			(layer "F.Fab")
			(hide yes)
			(effects
				(font
					(size 1.016 1.016)
					(thickness 0.1524)
				)
			)
		)
		(property "Device Type" "C603H36"
			(at 0 -4.3434 180)
			(unlocked yes)
			(layer "F.Fab")
			(hide yes)
			(effects
				(font
					(size 1.016 1.016)
					(thickness 0.1524)
				)
			)
		)
		(duplicate_pad_numbers_are_jumpers no)
		(fp_line
			(start 0.508 0)
			(end -0.508 0)
			(stroke
				(width 0.2032)
				(type default)
			)
			(layer "F.SilkS")
		)
		(fp_rect
			(start -0.5842 1.3335)
			(end 0.5842 -1.3335)
			(stroke
				(width 0)
				(type default)
			)
			(fill no)
			(layer "F.CrtYd")
		)
		(fp_rect
			(start -0.5842 1.3335)
			(end 0.5842 -1.3335)
			(stroke
				(width 0)
				(type default)
			)
			(fill no)
			(layer "F.Fab")
		)
		(pad "1" smd custom
			(at 0 -0.762 180)
			(size 0.2159 0.2159)
			(layers "F.Cu" "F.Mask" "F.Paste")
			(net "P12V_HDD34")
			(options
				(clearance outline)
				(anchor circle)
			)
			(primitives
				(gr_poly
					(pts
						(arc
							(start -0.3302 -0.4318)
							(mid -0.402042 -0.402042)
							(end -0.4318 -0.3302)
						)
						(arc
							(start -0.4318 0.3302)
							(mid -0.402042 0.402042)
							(end -0.3302 0.4318)
						)
						(arc
							(start 0.3302 0.4318)
							(mid 0.402042 0.402042)
							(end 0.4318 0.3302)
						)
						(arc
							(start 0.4318 -0.3302)
							(mid 0.402042 -0.402042)
							(end 0.3302 -0.4318)
						)
					)
					(width 0)
					(fill yes)
				)
			)
		)
		(pad "2" smd custom
			(at 0 0.762 180)
			(size 0.2159 0.2159)
			(layers "F.Cu" "F.Mask" "F.Paste")
			(net "GND")
			(options
				(clearance outline)
				(anchor circle)
			)
			(primitives
				(gr_poly
					(pts
						(arc
							(start -0.3302 -0.4318)
							(mid -0.402042 -0.402042)
							(end -0.4318 -0.3302)
						)
						(arc
							(start -0.4318 0.3302)
							(mid -0.402042 0.402042)
							(end -0.3302 0.4318)
						)
						(arc
							(start 0.3302 0.4318)
							(mid 0.402042 0.402042)
							(end 0.4318 0.3302)
						)
						(arc
							(start 0.4318 -0.3302)
							(mid 0.402042 -0.402042)
							(end 0.3302 -0.4318)
						)
					)
					(width 0)
					(fill yes)
				)
			)
		)
	)
	(footprint ""
		(layer "F.Cu")
		(at 172.593 -139.446 -90)
		(property "Reference" "R476"
			(at 0 0 270)
			(layer "F.SilkS")
			(hide yes)
			(effects
				(font
					(size 1.27 1.27)
				)
			)
		)
		(property "Value" "300KR2F-GP"
			(at 0.064008 -3.993896 270)
			(unlocked yes)
			(layer "F.Fab")
			(hide yes)
			(effects
				(font
					(size 1.016 1.016)
					(thickness 0.1524)
				)
			)
		)
		(property "Device Type" "R402H16"
			(at 0.064008 -5.517896 270)
			(unlocked yes)
			(layer "F.Fab")
			(hide yes)
			(effects
				(font
					(size 1.016 1.016)
					(thickness 0.1524)
				)
			)
		)
		(duplicate_pad_numbers_are_jumpers no)
		(fp_line
			(start -0.508 -0.9398)
			(end -0.508 0.9398)
			(stroke
				(width 0.1524)
				(type default)
			)
			(layer "F.SilkS")
		)
		(fp_line
			(start 0.508 -0.9398)
			(end -0.508 -0.9398)
			(stroke
				(width 0.1524)
				(type default)
			)
			(layer "F.SilkS")
		)
		(fp_rect
			(start -0.508 0.9398)
			(end 0.508 -0.9398)
			(stroke
				(width 0)
				(type default)
			)
			(fill no)
			(layer "F.CrtYd")
		)
		(fp_rect
			(start -0.508 0.9398)
			(end 0.508 -0.9398)
			(stroke
				(width 0)
				(type default)
			)
			(fill no)
			(layer "F.Fab")
		)
		(pad "1" smd custom
			(at 0 -0.4445 270)
			(size 0.1397 0.1397)
			(layers "F.Cu" "F.Mask" "F.Paste")
			(net "SW_HDD_N17")
			(options
				(clearance outline)
				(anchor circle)
			)
			(primitives
				(gr_poly
					(pts
						(arc
							(start -0.1778 -0.2794)
							(mid -0.249642 -0.249642)
							(end -0.2794 -0.1778)
						)
						(arc
							(start -0.2794 0.1778)
							(mid -0.249642 0.249642)
							(end -0.1778 0.2794)
						)
						(arc
							(start 0.1778 0.2794)
							(mid 0.249642 0.249642)
							(end 0.2794 0.1778)
						)
						(arc
							(start 0.2794 -0.1778)
							(mid 0.249642 -0.249642)
							(end 0.1778 -0.2794)
						)
					)
					(width 0)
					(fill yes)
				)
			)
		)
		(pad "2" smd custom
			(at 0 0.4445 270)
			(size 0.1397 0.1397)
			(layers "F.Cu" "F.Mask" "F.Paste")
			(net "P12V_B")
			(options
				(clearance outline)
				(anchor circle)
			)
			(primitives
				(gr_poly
					(pts
						(arc
							(start -0.1778 -0.2794)
							(mid -0.249642 -0.249642)
							(end -0.2794 -0.1778)
						)
						(arc
							(start -0.2794 0.1778)
							(mid -0.249642 0.249642)
							(end -0.1778 0.2794)
						)
						(arc
							(start 0.1778 0.2794)
							(mid 0.249642 0.249642)
							(end 0.2794 0.1778)
						)
						(arc
							(start 0.2794 -0.1778)
							(mid 0.249642 -0.249642)
							(end 0.1778 -0.2794)
						)
					)
					(width 0)
					(fill yes)
				)
			)
		)
	)
	(footprint ""
		(layer "F.Cu")
		(at 246.155972 -135.665718 -90)
		(property "Reference" "C37"
			(at 0 0 270)
			(layer "F.SilkS")
			(hide yes)
			(effects
				(font
					(size 1.27 1.27)
				)
			)
		)
		(property "Value" "SC1U16V3KX-5GP"
			(at 0 -2.8194 270)
			(unlocked yes)
			(layer "F.Fab")
			(hide yes)
			(effects
				(font
					(size 1.016 1.016)
					(thickness 0.1524)
				)
			)
		)
		(property "Device Type" "C603H36"
			(at 0 -4.3434 270)
			(unlocked yes)
			(layer "F.Fab")
			(hide yes)
			(effects
				(font
					(size 1.016 1.016)
					(thickness 0.1524)
				)
			)
		)
		(duplicate_pad_numbers_are_jumpers no)
		(fp_line
			(start 0.508 0)
			(end -0.508 0)
			(stroke
				(width 0.2032)
				(type default)
			)
			(layer "F.SilkS")
		)
		(fp_rect
			(start -0.5842 1.3335)
			(end 0.5842 -1.3335)
			(stroke
				(width 0)
				(type default)
			)
			(fill no)
			(layer "F.CrtYd")
		)
		(fp_rect
			(start -0.5842 1.3335)
			(end 0.5842 -1.3335)
			(stroke
				(width 0)
				(type default)
			)
			(fill no)
			(layer "F.Fab")
		)
		(pad "1" smd custom
			(at 0 -0.762 270)
			(size 0.2159 0.2159)
			(layers "F.Cu" "F.Mask" "F.Paste")
			(net "P3V3_STBY_B")
			(options
				(clearance outline)
				(anchor circle)
			)
			(primitives
				(gr_poly
					(pts
						(arc
							(start -0.3302 -0.4318)
							(mid -0.402042 -0.402042)
							(end -0.4318 -0.3302)
						)
						(arc
							(start -0.4318 0.3302)
							(mid -0.402042 0.402042)
							(end -0.3302 0.4318)
						)
						(arc
							(start 0.3302 0.4318)
							(mid 0.402042 0.402042)
							(end 0.4318 0.3302)
						)
						(arc
							(start 0.4318 -0.3302)
							(mid 0.402042 -0.402042)
							(end 0.3302 -0.4318)
						)
					)
					(width 0)
					(fill yes)
				)
			)
		)
		(pad "2" smd custom
			(at 0 0.762 270)
			(size 0.2159 0.2159)
			(layers "F.Cu" "F.Mask" "F.Paste")
			(net "GND")
			(options
				(clearance outline)
				(anchor circle)
			)
			(primitives
				(gr_poly
					(pts
						(arc
							(start -0.3302 -0.4318)
							(mid -0.402042 -0.402042)
							(end -0.4318 -0.3302)
						)
						(arc
							(start -0.4318 0.3302)
							(mid -0.402042 0.402042)
							(end -0.3302 0.4318)
						)
						(arc
							(start 0.3302 0.4318)
							(mid 0.402042 0.402042)
							(end 0.4318 0.3302)
						)
						(arc
							(start 0.4318 -0.3302)
							(mid 0.402042 -0.402042)
							(end 0.3302 -0.4318)
						)
					)
					(width 0)
					(fill yes)
				)
			)
		)
	)
	(footprint ""
		(layer "F.Cu")
		(at 191.135 -267.081 180)
		(property "Reference" "R241"
			(at 0 0 180)
			(layer "F.SilkS")
			(hide yes)
			(effects
				(font
					(size 1.27 1.27)
				)
			)
		)
		(property "Value" "220R3F-1-GP"
			(at -0.0254 -2.5146 180)
			(unlocked yes)
			(layer "F.Fab")
			(hide yes)
			(effects
				(font
					(size 1.016 1.016)
					(thickness 0.1524)
				)
			)
		)
		(property "Device Type" "R603H22"
			(at -0.0254 -4.0386 180)
			(unlocked yes)
			(layer "F.Fab")
			(hide yes)
			(effects
				(font
					(size 1.016 1.016)
					(thickness 0.1524)
				)
			)
		)
		(duplicate_pad_numbers_are_jumpers no)
		(fp_line
			(start 0.2032 0)
			(end 0.4826 0)
			(stroke
				(width 0.2032)
				(type default)
			)
			(layer "F.SilkS")
		)
		(fp_line
			(start -0.4826 0)
			(end -0.2032 0)
			(stroke
				(width 0.2032)
				(type default)
			)
			(layer "F.SilkS")
		)
		(fp_rect
			(start -0.5842 1.3335)
			(end 0.5842 -1.3335)
			(stroke
				(width 0)
				(type default)
			)
			(fill no)
			(layer "F.CrtYd")
		)
		(fp_rect
			(start -0.5842 1.3335)
			(end 0.5842 -1.3335)
			(stroke
				(width 0)
				(type default)
			)
			(fill no)
			(layer "F.Fab")
		)
		(pad "1" smd custom
			(at 0 -0.762 180)
			(size 0.2159 0.2159)
			(layers "F.Cu" "F.Mask" "F.Paste")
			(net "HDD_PRSNT_5")
			(options
				(clearance outline)
				(anchor circle)
			)
			(primitives
				(gr_poly
					(pts
						(arc
							(start -0.3302 -0.4318)
							(mid -0.402042 -0.402042)
							(end -0.4318 -0.3302)
						)
						(arc
							(start -0.4318 0.3302)
							(mid -0.402042 0.402042)
							(end -0.3302 0.4318)
						)
						(arc
							(start 0.3302 0.4318)
							(mid 0.402042 0.402042)
							(end 0.4318 0.3302)
						)
						(arc
							(start 0.4318 -0.3302)
							(mid 0.402042 -0.402042)
							(end 0.3302 -0.4318)
						)
					)
					(width 0)
					(fill yes)
				)
			)
		)
		(pad "2" smd custom
			(at 0 0.762 180)
			(size 0.2159 0.2159)
			(layers "F.Cu" "F.Mask" "F.Paste")
			(net "DRIVE_B_5_INS")
			(options
				(clearance outline)
				(anchor circle)
			)
			(primitives
				(gr_poly
					(pts
						(arc
							(start -0.3302 -0.4318)
							(mid -0.402042 -0.402042)
							(end -0.4318 -0.3302)
						)
						(arc
							(start -0.4318 0.3302)
							(mid -0.402042 0.402042)
							(end -0.3302 0.4318)
						)
						(arc
							(start 0.3302 0.4318)
							(mid 0.402042 0.402042)
							(end 0.4318 0.3302)
						)
						(arc
							(start 0.4318 -0.3302)
							(mid 0.402042 -0.402042)
							(end 0.3302 -0.4318)
						)
					)
					(width 0)
					(fill yes)
				)
			)
		)
	)
	(footprint ""
		(layer "F.Cu")
		(at 80.137 -99.314)
		(property "Reference" "R402"
			(at 0 0 0)
			(layer "F.SilkS")
			(hide yes)
			(effects
				(font
					(size 1.27 1.27)
				)
			)
		)
		(property "Value" "130R3F-GP"
			(at -0.0254 -2.5146 0)
			(unlocked yes)
			(layer "F.Fab")
			(hide yes)
			(effects
				(font
					(size 1.016 1.016)
					(thickness 0.1524)
				)
			)
		)
		(property "Device Type" "R603H22"
			(at -0.0254 -4.0386 0)
			(unlocked yes)
			(layer "F.Fab")
			(hide yes)
			(effects
				(font
					(size 1.016 1.016)
					(thickness 0.1524)
				)
			)
		)
		(duplicate_pad_numbers_are_jumpers no)
		(fp_line
			(start -0.4826 0)
			(end -0.2032 0)
			(stroke
				(width 0.2032)
				(type default)
			)
			(layer "F.SilkS")
		)
		(fp_line
			(start 0.2032 0)
			(end 0.4826 0)
			(stroke
				(width 0.2032)
				(type default)
			)
			(layer "F.SilkS")
		)
		(fp_rect
			(start -0.5842 1.3335)
			(end 0.5842 -1.3335)
			(stroke
				(width 0)
				(type default)
			)
			(fill no)
			(layer "F.CrtYd")
		)
		(fp_rect
			(start -0.5842 1.3335)
			(end 0.5842 -1.3335)
			(stroke
				(width 0)
				(type default)
			)
			(fill no)
			(layer "F.Fab")
		)
		(pad "1" smd custom
			(at 0 -0.762)
			(size 0.2159 0.2159)
			(layers "F.Cu" "F.Mask" "F.Paste")
			(net "P5V_B_1")
			(options
				(clearance outline)
				(anchor circle)
			)
			(primitives
				(gr_poly
					(pts
						(arc
							(start -0.3302 -0.4318)
							(mid -0.402042 -0.402042)
							(end -0.4318 -0.3302)
						)
						(arc
							(start -0.4318 0.3302)
							(mid -0.402042 0.402042)
							(end -0.3302 0.4318)
						)
						(arc
							(start 0.3302 0.4318)
							(mid 0.402042 0.402042)
							(end 0.4318 0.3302)
						)
						(arc
							(start 0.4318 -0.3302)
							(mid 0.402042 -0.402042)
							(end 0.3302 -0.4318)
						)
					)
					(width 0)
					(fill yes)
				)
			)
		)
		(pad "2" smd custom
			(at 0 0.762)
			(size 0.2159 0.2159)
			(layers "F.Cu" "F.Mask" "F.Paste")
			(net "FLT_HDD14")
			(options
				(clearance outline)
				(anchor circle)
			)
			(primitives
				(gr_poly
					(pts
						(arc
							(start -0.3302 -0.4318)
							(mid -0.402042 -0.402042)
							(end -0.4318 -0.3302)
						)
						(arc
							(start -0.4318 0.3302)
							(mid -0.402042 0.402042)
							(end -0.3302 0.4318)
						)
						(arc
							(start 0.3302 0.4318)
							(mid 0.402042 0.402042)
							(end 0.4318 0.3302)
						)
						(arc
							(start 0.4318 -0.3302)
							(mid 0.402042 -0.402042)
							(end 0.3302 -0.4318)
						)
					)
					(width 0)
					(fill yes)
				)
			)
		)
	)
)
